# T6G (Grand Teton) — schematic netlist excerpt (pin names and nets, part order shuffled) for the footprints in the layout excerpt that follows; sources: Cadence DE-HDL packaged netlist, KiCad conversion of 04192023_DAF0TMB3IC0_F0TG_MB_C_brd_V02_OCP.brd

Q39  MOSFET_NCH_GDS_ESD_PROTECTED  2N7002K IC  pkg SOT23_GDSXC  page 152
  D  = P12V_SCM_EN
  G  = FM_SCM_PRSNT1_R_N
  S  = GND

R2488  Q_RES  4.7K 1% CHIP  pkg 0402LF  page 133 : A = P3V3_AUX ; B = OCP_SFF_WAKE_BUFF_N

(kicad_pcb
	(version 20260206)
	(generator "pcbnew")
	(generator_version "10.0")
	(general
		(thickness 1.6)
		(legacy_teardrops no)
	)
	(paper "A4")
	(title_block
		(title "04192023_DAF0TMB3IC0_F0TG_MB_C_brd_V02_OCP.brd")
		(comment 1 "Grand Teton / footprints 1538-1539 of 8354")
	)
	(layers
		(0 "F.Cu" signal "TOP")
		(4 "In1.Cu" signal "GND")
		(6 "In2.Cu" signal "IN1")
		(8 "In3.Cu" signal "GND1")
		(10 "In4.Cu" signal "IN2")
		(12 "In5.Cu" signal "GND2")
		(14 "In6.Cu" signal "IN3")
		(16 "In7.Cu" signal "GND3")
		(18 "In8.Cu" signal "VCC")
		(20 "In9.Cu" signal "VCC1")
		(22 "In10.Cu" signal "GND4")
		(24 "In11.Cu" signal "IN4")
		(26 "In12.Cu" signal "GND5")
		(28 "In13.Cu" signal "IN5")
		(30 "In14.Cu" signal "GND6")
		(32 "In15.Cu" signal "IN6")
		(34 "In16.Cu" signal "GND7")
		(2 "B.Cu" signal "BOTTOM")
		(9 "F.Adhes" user "F.Adhesive")
		(11 "B.Adhes" user "B.Adhesive")
		(13 "F.Paste" user "Package Geometry/Pastemask Top")
		(15 "B.Paste" user "Package Geometry/Pastemask Bottom")
		(5 "F.SilkS" user "Ref Des/Silkscreen Top")
		(7 "B.SilkS" user "Ref Des/Silkscreen Bottom")
		(1 "F.Mask" user "Board Geometry/Soldermask Top")
		(3 "B.Mask" user "Board Geometry/Soldermask Bottom")
		(17 "Dwgs.User" user "User.Drawings")
		(19 "Cmts.User" user "User.Comments")
		(21 "Eco1.User" user "User.Eco1")
		(23 "Eco2.User" user "User.Eco2")
		(25 "Edge.Cuts" user "Board Geometry/Outline")
		(27 "Margin" user)
		(31 "F.CrtYd" user "Package Geometry/Place Bound Top")
		(29 "B.CrtYd" user "Package Geometry/Place Bound Bottom")
		(35 "F.Fab" user "Ref Des/Assembly Top")
		(33 "B.Fab" user "Ref Des/Assembly Bottom")
	)
	(footprint ""
		(layer "F.Cu")
		(at 193.809366 -37.43325 90)
		(property "Reference" "Q39"
			(at -2.361946 -0.526796 0)
			(unlocked yes)
			(layer "F.SilkS")
			(effects
				(font
					(size 0.7874 0.5842)
					(thickness 0.1524)
				)
				(justify left)
			)
		)
		(property "Value" ""
			(at 0 0 90)
			(layer "F.Fab")
			(effects
				(font
					(size 1.27 1.27)
				)
			)
		)
		(duplicate_pad_numbers_are_jumpers no)
		(fp_line
			(start 1.603248 -1.500124)
			(end 1.603248 1.500124)
			(stroke
				(width 0.1524)
				(type default)
			)
			(layer "F.SilkS")
		)
		(fp_line
			(start -1.603248 -1.500124)
			(end 1.603248 -1.500124)
			(stroke
				(width 0.1524)
				(type default)
			)
			(layer "F.SilkS")
		)
		(fp_line
			(start 1.603248 1.500124)
			(end -1.603248 1.500124)
			(stroke
				(width 0.1524)
				(type default)
			)
			(layer "F.SilkS")
		)
		(fp_line
			(start -1.603248 1.500124)
			(end -1.603248 -1.500124)
			(stroke
				(width 0.1524)
				(type default)
			)
			(layer "F.SilkS")
		)
		(fp_line
			(start 0.700024 -1.500124)
			(end -0.700024 -1.500124)
			(stroke
				(width 0.1)
				(type default)
			)
			(layer "F.Fab")
		)
		(fp_line
			(start -0.700024 -1.500124)
			(end -0.700024 -1.169924)
			(stroke
				(width 0.1)
				(type default)
			)
			(layer "F.Fab")
		)
		(fp_line
			(start -0.700024 -1.169924)
			(end -1.249934 -1.169924)
			(stroke
				(width 0.1)
				(type default)
			)
			(layer "F.Fab")
		)
		(fp_line
			(start -1.249934 -1.169924)
			(end -1.249934 -0.729996)
			(stroke
				(width 0.1)
				(type default)
			)
			(layer "F.Fab")
		)
		(fp_line
			(start -0.6985 -0.729996)
			(end -0.6985 0.729996)
			(stroke
				(width 0.1)
				(type default)
			)
			(layer "F.Fab")
		)
		(fp_line
			(start -1.249934 -0.729996)
			(end -0.6985 -0.729996)
			(stroke
				(width 0.1)
				(type default)
			)
			(layer "F.Fab")
		)
		(fp_line
			(start 1.249934 -0.219964)
			(end 0.700024 -0.219964)
			(stroke
				(width 0.1)
				(type default)
			)
			(layer "F.Fab")
		)
		(fp_line
			(start 0.700024 -0.219964)
			(end 0.700024 -1.500124)
			(stroke
				(width 0.1)
				(type default)
			)
			(layer "F.Fab")
		)
		(fp_line
			(start 1.249934 0.219964)
			(end 1.249934 -0.219964)
			(stroke
				(width 0.1)
				(type default)
			)
			(layer "F.Fab")
		)
		(fp_line
			(start 0.700024 0.219964)
			(end 1.249934 0.219964)
			(stroke
				(width 0.1)
				(type default)
			)
			(layer "F.Fab")
		)
		(fp_line
			(start -0.6985 0.729996)
			(end -1.249934 0.729996)
			(stroke
				(width 0.1)
				(type default)
			)
			(layer "F.Fab")
		)
		(fp_line
			(start -1.249934 0.729996)
			(end -1.249934 1.169924)
			(stroke
				(width 0.1)
				(type default)
			)
			(layer "F.Fab")
		)
		(fp_line
			(start -0.700024 1.169924)
			(end -0.700024 1.500124)
			(stroke
				(width 0.1)
				(type default)
			)
			(layer "F.Fab")
		)
		(fp_line
			(start -1.249934 1.169924)
			(end -0.700024 1.169924)
			(stroke
				(width 0.1)
				(type default)
			)
			(layer "F.Fab")
		)
		(fp_line
			(start 0.700024 1.500124)
			(end 0.700024 0.219964)
			(stroke
				(width 0.1)
				(type default)
			)
			(layer "F.Fab")
		)
		(fp_line
			(start -0.700024 1.500124)
			(end 0.700024 1.500124)
			(stroke
				(width 0.1)
				(type default)
			)
			(layer "F.Fab")
		)
		(fp_rect
			(start -0.700024 1.500124)
			(end 0.700024 -1.500124)
			(stroke
				(width 0)
				(type default)
			)
			(fill no)
			(layer "F.Fab")
		)
		(pad "D" smd rect
			(at 0.999998 0)
			(size 0.8128 0.9144)
			(layers "F.Cu" "F.Mask" "F.Paste")
			(net "P12V_SCM_EN")
		)
		(pad "G" smd rect
			(at -0.999998 -0.94996)
			(size 0.8128 0.9144)
			(layers "F.Cu" "F.Mask" "F.Paste")
			(net "FM_SCM_PRSNT1_R_N")
		)
		(pad "S" smd rect
			(at -0.999998 0.94996)
			(size 0.8128 0.9144)
			(layers "F.Cu" "F.Mask" "F.Paste")
			(net "GND")
		)
	)
	(footprint ""
		(layer "F.Cu")
		(at 463.18932 -38.565836 180)
		(property "Reference" "R2488"
			(at 0 0 180)
			(layer "F.SilkS")
			(hide yes)
			(effects
				(font
					(size 1.27 1.27)
				)
			)
		)
		(property "Value" ""
			(at 0 0 180)
			(layer "F.Fab")
			(effects
				(font
					(size 1.27 1.27)
				)
			)
		)
		(duplicate_pad_numbers_are_jumpers no)
		(fp_line
			(start 0.7874 0.4064)
			(end -0.7874 0.4064)
			(stroke
				(width 0.1524)
				(type default)
			)
			(layer "F.SilkS")
		)
		(fp_line
			(start 0.7874 -0.4064)
			(end 0.7874 0.4064)
			(stroke
				(width 0.1524)
				(type default)
			)
			(layer "F.SilkS")
		)
		(fp_line
			(start -0.7874 0.4064)
			(end -0.7874 -0.4064)
			(stroke
				(width 0.1524)
				(type default)
			)
			(layer "F.SilkS")
		)
		(fp_line
			(start -0.7874 -0.4064)
			(end 0.7874 -0.4064)
			(stroke
				(width 0.1524)
				(type default)
			)
			(layer "F.SilkS")
		)
		(fp_line
			(start 0.67945 0.3048)
			(end 0.120396 0.3048)
			(stroke
				(width 0.1)
				(type default)
			)
			(layer "F.Fab")
		)
		(fp_line
			(start 0.67945 -0.3048)
			(end 0.67945 0.3048)
			(stroke
				(width 0.1)
				(type default)
			)
			(layer "F.Fab")
		)
		(fp_line
			(start 0.12065 -0.2794)
			(end 0.12065 -0.3048)
			(stroke
				(width 0.1)
				(type default)
			)
			(layer "F.Fab")
		)
		(fp_line
			(start 0.12065 -0.3048)
			(end 0.67945 -0.3048)
			(stroke
				(width 0.1)
				(type default)
			)
			(layer "F.Fab")
		)
		(fp_line
			(start 0.120396 0.3048)
			(end 0.120396 0.2794)
			(stroke
				(width 0.1)
				(type default)
			)
			(layer "F.Fab")
		)
		(fp_line
			(start 0.120396 0.2794)
			(end -0.12065 0.2794)
			(stroke
				(width 0.1)
				(type default)
			)
			(layer "F.Fab")
		)
		(fp_line
			(start -0.12065 0.3048)
			(end -0.67945 0.3048)
			(stroke
				(width 0.1)
				(type default)
			)
			(layer "F.Fab")
		)
		(fp_line
			(start -0.12065 0.2794)
			(end -0.12065 0.3048)
			(stroke
				(width 0.1)
				(type default)
			)
			(layer "F.Fab")
		)
		(fp_line
			(start -0.12065 -0.2794)
			(end 0.12065 -0.2794)
			(stroke
				(width 0.1)
				(type default)
			)
			(layer "F.Fab")
		)
		(fp_line
			(start -0.12065 -0.305054)
			(end -0.12065 -0.2794)
			(stroke
				(width 0.1)
				(type default)
			)
			(layer "F.Fab")
		)
		(fp_line
			(start -0.67945 0.3048)
			(end -0.67945 -0.305054)
			(stroke
				(width 0.1)
				(type default)
			)
			(layer "F.Fab")
		)
		(fp_line
			(start -0.67945 -0.305054)
			(end -0.12065 -0.305054)
			(stroke
				(width 0.1)
				(type default)
			)
			(layer "F.Fab")
		)
		(pad "1" smd circle
			(at -0.40005 0 180)
			(size 0 0)
			(layers "F.Cu" "F.Mask" "F.Paste")
			(net "P3V3_AUX")
		)
		(pad "2" smd circle
			(at 0.40005 0 180)
			(size 0 0)
			(layers "F.Cu" "F.Mask" "F.Paste")
			(net "OCP_SFF_WAKE_BUFF_N")
		)
	)
)
